(kicad_pcb
	(version 20260206)
	(generator "pcbnew")
	(generator_version "10.0")
	(general
		(thickness 1.6)
		(legacy_teardrops no)
	)
	(paper "A4")
	(title_block
		(title "Wiwynn_Tioga_Pass_MB.brd")
		(comment 1 "Tioga Pass / footprints 4377-4383 of 4770")
	)
	(layers
		(0 "F.Cu" signal "TOP")
		(4 "In1.Cu" signal "L2GND")
		(6 "In2.Cu" signal "L3")
		(8 "In3.Cu" signal "L4GND")
		(10 "In4.Cu" signal "L5")
		(12 "In5.Cu" signal "L6GND")
		(14 "In6.Cu" signal "L7VCC")
		(16 "In7.Cu" signal "L8VCC")
		(18 "In8.Cu" signal "L9GND")
		(20 "In9.Cu" signal "L10")
		(22 "In10.Cu" signal "L11GND")
		(24 "In11.Cu" signal "L12")
		(26 "In12.Cu" signal "L13GND")
		(2 "B.Cu" signal "BOTTOM")
		(9 "F.Adhes" user "F.Adhesive")
		(11 "B.Adhes" user "B.Adhesive")
		(13 "F.Paste" user "Package Geometry/Pastemask Top")
		(15 "B.Paste" user "Package Geometry/Pastemask Bottom")
		(5 "F.SilkS" user "Ref Des/Silkscreen Top")
		(7 "B.SilkS" user "Ref Des/Silkscreen Bottom")
		(1 "F.Mask" user "Board Geometry/Soldermask Top")
		(3 "B.Mask" user "Board Geometry/Soldermask Bottom")
		(17 "Dwgs.User" user "User.Drawings")
		(19 "Cmts.User" user "User.Comments")
		(21 "Eco1.User" user "User.Eco1")
		(23 "Eco2.User" user "User.Eco2")
		(25 "Edge.Cuts" user "Board Geometry/Outline")
		(27 "Margin" user)
		(31 "F.CrtYd" user "Package Geometry/Place Bound Top")
		(29 "B.CrtYd" user "Package Geometry/Place Bound Bottom")
		(35 "F.Fab" user "Ref Des/Assembly Top")
		(33 "B.Fab" user "Ref Des/Assembly Bottom")
	)
	(footprint ""
		(layer "B.Cu")
		(at 411.861 -6.5405)
		(property "Reference" "R2P18"
			(at 0 0 0)
			(layer "B.SilkS")
			(hide yes)
			(effects
				(font
					(size 1.27 1.27)
				)
				(justify mirror)
			)
		)
		(property "Value" ""
			(at 0 0 0)
			(layer "B.Fab")
			(effects
				(font
					(size 1.27 1.27)
				)
				(justify mirror)
			)
		)
		(duplicate_pad_numbers_are_jumpers no)
		(fp_poly
			(pts
				(xy 0.2794 -0.1016) (xy -0.2794 -0.1016) (xy -0.2794 0.9906) (xy 0.2794 0.9906)
			)
			(stroke
				(width 0)
				(type default)
			)
			(fill no)
			(layer "B.CrtYd")
		)
		(fp_line
			(start -0.2794 -0.1016)
			(end 0.2794 -0.1016)
			(stroke
				(width 0.1)
				(type default)
			)
			(layer "B.Fab")
		)
		(fp_line
			(start -0.2794 0.9906)
			(end -0.2794 -0.1016)
			(stroke
				(width 0.1)
				(type default)
			)
			(layer "B.Fab")
		)
		(fp_line
			(start 0.2794 -0.1016)
			(end 0.2794 0.9906)
			(stroke
				(width 0.1)
				(type default)
			)
			(layer "B.Fab")
		)
		(fp_line
			(start 0.2794 0.9906)
			(end -0.2794 0.9906)
			(stroke
				(width 0.1)
				(type default)
			)
			(layer "B.Fab")
		)
		(pad "1" smd rect
			(at 0 0 180)
			(size 0.508 0.508)
			(layers "B.Cu" "B.Mask" "B.Paste")
			(net "P3V3_STBY")
		)
		(pad "2" smd rect
			(at 0 0.889 180)
			(size 0.508 0.508)
			(layers "B.Cu" "B.Mask" "B.Paste")
			(net "PWRGD_P5V_N")
		)
		(zone
			(layer "B.Cu")
			(hatch none 0.5)
			(connect_pads
				(clearance 0)
			)
			(min_thickness 0.25)
			(keepout
				(tracks allowed)
				(vias not_allowed)
				(pads allowed)
				(copperpour not_allowed)
				(footprints allowed)
			)
			(placement
				(enabled no)
				(sheetname "")
			)
			(fill
				(thermal_gap 0.5)
				(thermal_bridge_width 0.5)
				(island_removal_mode 0)
			)
			(polygon
				(pts
					(xy 412.115 -6.2865) (xy 411.607 -6.2865) (xy 411.607 -5.9055) (xy 412.115 -5.9055)
				)
			)
		)
		(zone
			(layer "B.Cu")
			(hatch none 0.5)
			(connect_pads
				(clearance 0)
			)
			(min_thickness 0.25)
			(keepout
				(tracks not_allowed)
				(vias allowed)
				(pads allowed)
				(copperpour not_allowed)
				(footprints allowed)
			)
			(placement
				(enabled no)
				(sheetname "")
			)
			(fill
				(thermal_gap 0.5)
				(thermal_bridge_width 0.5)
				(island_removal_mode 0)
			)
			(polygon
				(pts
					(xy 412.115 -5.9055) (xy 411.607 -5.9055) (xy 411.607 -6.2865) (xy 412.115 -6.2865)
				)
			)
		)
	)
	(footprint ""
		(layer "B.Cu")
		(at 372.351046 -75.4888)
		(property "Reference" "C3P47"
			(at 0 0 0)
			(layer "B.SilkS")
			(hide yes)
			(effects
				(font
					(size 1.27 1.27)
				)
				(justify mirror)
			)
		)
		(property "Value" ""
			(at 0 0 0)
			(layer "B.Fab")
			(effects
				(font
					(size 1.27 1.27)
				)
				(justify mirror)
			)
		)
		(duplicate_pad_numbers_are_jumpers no)
		(fp_rect
			(start 0.2794 0.9144)
			(end -0.2794 -0.1143)
			(stroke
				(width 0)
				(type default)
			)
			(fill no)
			(layer "B.CrtYd")
		)
		(fp_line
			(start -0.2794 -0.1143)
			(end -0.2794 0.9144)
			(stroke
				(width 0.1)
				(type default)
			)
			(layer "B.Fab")
		)
		(fp_line
			(start -0.2794 0.9144)
			(end 0.2794 0.9144)
			(stroke
				(width 0.1)
				(type default)
			)
			(layer "B.Fab")
		)
		(fp_line
			(start 0.2794 -0.1143)
			(end -0.2794 -0.1143)
			(stroke
				(width 0.1)
				(type default)
			)
			(layer "B.Fab")
		)
		(fp_line
			(start 0.2794 0.9144)
			(end 0.2794 -0.1143)
			(stroke
				(width 0.1)
				(type default)
			)
			(layer "B.Fab")
		)
		(pad "1" smd custom
			(at 0 0 270)
			(size 0.10414 0.10414)
			(layers "B.Cu" "B.Mask" "B.Paste")
			(net "P3V3_STBY")
			(options
				(clearance outline)
				(anchor circle)
			)
			(primitives
				(gr_poly
					(pts
						(xy -0.20828 -0.08636) (xy -0.20828 0.08636) (xy -0.08636 0.20828) (xy 0.086614 0.20828) (xy 0.20828 0.086614)
						(xy 0.20828 -0.08636) (xy 0.08636 -0.20828) (xy -0.08636 -0.20828)
					)
					(width 0)
					(fill yes)
				)
			)
		)
		(pad "2" smd custom
			(at 0 0.8001 270)
			(size 0.10414 0.10414)
			(layers "B.Cu" "B.Mask" "B.Paste")
			(net "GND")
			(options
				(clearance outline)
				(anchor circle)
			)
			(primitives
				(gr_poly
					(pts
						(xy -0.20828 -0.08636) (xy -0.20828 0.08636) (xy -0.08636 0.20828) (xy 0.086614 0.20828) (xy 0.20828 0.086614)
						(xy 0.20828 -0.08636) (xy 0.08636 -0.20828) (xy -0.08636 -0.20828)
					)
					(width 0)
					(fill yes)
				)
			)
		)
		(zone
			(layer "B.Cu")
			(hatch none 0.5)
			(connect_pads
				(clearance 0)
			)
			(min_thickness 0.25)
			(keepout
				(tracks not_allowed)
				(vias allowed)
				(pads allowed)
				(copperpour not_allowed)
				(footprints allowed)
			)
			(placement
				(enabled no)
				(sheetname "")
			)
			(fill
				(thermal_gap 0.5)
				(thermal_bridge_width 0.5)
				(island_removal_mode 0)
			)
			(polygon
				(pts
					(xy 372.438676 -75.27925) (xy 372.438676 -74.89825) (xy 372.263416 -74.89825) (xy 372.263162 -75.27925)
				)
			)
		)
		(zone
			(layer "B.Cu")
			(hatch none 0.5)
			(connect_pads
				(clearance 0)
			)
			(min_thickness 0.25)
			(keepout
				(tracks allowed)
				(vias not_allowed)
				(pads allowed)
				(copperpour not_allowed)
				(footprints allowed)
			)
			(placement
				(enabled no)
				(sheetname "")
			)
			(fill
				(thermal_gap 0.5)
				(thermal_bridge_width 0.5)
				(island_removal_mode 0)
			)
			(polygon
				(pts
					(xy 372.438676 -75.27925) (xy 372.438676 -74.89825) (xy 372.263416 -74.89825) (xy 372.263162 -75.27925)
				)
			)
		)
	)
	(footprint ""
		(layer "B.Cu")
		(at 396.674086 -30.627574 180)
		(property "Reference" "R2T28"
			(at 0 0 0)
			(layer "B.SilkS")
			(hide yes)
			(effects
				(font
					(size 1.27 1.27)
				)
				(justify mirror)
			)
		)
		(property "Value" ""
			(at 0 0 0)
			(layer "B.Fab")
			(effects
				(font
					(size 1.27 1.27)
				)
				(justify mirror)
			)
		)
		(duplicate_pad_numbers_are_jumpers no)
		(fp_poly
			(pts
				(xy 0.2794 -0.1016) (xy -0.2794 -0.1016) (xy -0.2794 0.9906) (xy 0.2794 0.9906)
			)
			(stroke
				(width 0)
				(type default)
			)
			(fill no)
			(layer "B.CrtYd")
		)
		(fp_line
			(start 0.2794 0.9906)
			(end -0.2794 0.9906)
			(stroke
				(width 0.1)
				(type default)
			)
			(layer "B.Fab")
		)
		(fp_line
			(start 0.2794 -0.1016)
			(end 0.2794 0.9906)
			(stroke
				(width 0.1)
				(type default)
			)
			(layer "B.Fab")
		)
		(fp_line
			(start -0.2794 0.9906)
			(end -0.2794 -0.1016)
			(stroke
				(width 0.1)
				(type default)
			)
			(layer "B.Fab")
		)
		(fp_line
			(start -0.2794 -0.1016)
			(end 0.2794 -0.1016)
			(stroke
				(width 0.1)
				(type default)
			)
			(layer "B.Fab")
		)
		(pad "1" smd rect
			(at 0 0)
			(size 0.508 0.508)
			(layers "B.Cu" "B.Mask" "B.Paste")
			(net "FM_PCH_PWRBTN_R_N")
		)
		(pad "2" smd rect
			(at 0 0.889)
			(size 0.508 0.508)
			(layers "B.Cu" "B.Mask" "B.Paste")
			(net "FM_PCH_PWRBTN_N")
		)
		(zone
			(layer "B.Cu")
			(hatch none 0.5)
			(connect_pads
				(clearance 0)
			)
			(min_thickness 0.25)
			(keepout
				(tracks not_allowed)
				(vias allowed)
				(pads allowed)
				(copperpour not_allowed)
				(footprints allowed)
			)
			(placement
				(enabled no)
				(sheetname "")
			)
			(fill
				(thermal_gap 0.5)
				(thermal_bridge_width 0.5)
				(island_removal_mode 0)
			)
			(polygon
				(pts
					(xy 396.420086 -31.262574) (xy 396.928086 -31.262574) (xy 396.928086 -30.881574) (xy 396.420086 -30.881574)
				)
			)
		)
		(zone
			(layer "B.Cu")
			(hatch none 0.5)
			(connect_pads
				(clearance 0)
			)
			(min_thickness 0.25)
			(keepout
				(tracks allowed)
				(vias not_allowed)
				(pads allowed)
				(copperpour not_allowed)
				(footprints allowed)
			)
			(placement
				(enabled no)
				(sheetname "")
			)
			(fill
				(thermal_gap 0.5)
				(thermal_bridge_width 0.5)
				(island_removal_mode 0)
			)
			(polygon
				(pts
					(xy 396.420086 -30.881574) (xy 396.928086 -30.881574) (xy 396.928086 -31.262574) (xy 396.420086 -31.262574)
				)
			)
		)
	)
	(footprint ""
		(layer "B.Cu")
		(at 331.8002 -135.4074 90)
		(property "Reference" "C4M1"
			(at -3.36423 1.43002 0)
			(unlocked yes)
			(layer "B.SilkS")
			(effects
				(font
					(size 0.7874 0.5842)
					(thickness 0.1524)
				)
				(justify left mirror)
			)
		)
		(property "Value" ""
			(at 0 0 90)
			(layer "B.Fab")
			(effects
				(font
					(size 1.27 1.27)
				)
				(justify mirror)
			)
		)
		(duplicate_pad_numbers_are_jumpers no)
		(fp_line
			(start 2.032 -1.524)
			(end 2.032 1.524)
			(stroke
				(width 0.1524)
				(type default)
			)
			(layer "B.SilkS")
		)
		(fp_line
			(start 1.7272 -1.524)
			(end 2.032 -1.524)
			(stroke
				(width 0.1524)
				(type default)
			)
			(layer "B.SilkS")
		)
		(fp_line
			(start -1.7272 -1.524)
			(end -2.032 -1.524)
			(stroke
				(width 0.1524)
				(type default)
			)
			(layer "B.SilkS")
		)
		(fp_line
			(start -2.032 -1.524)
			(end -2.032 1.524)
			(stroke
				(width 0.1524)
				(type default)
			)
			(layer "B.SilkS")
		)
		(fp_line
			(start 2.2987 -0.2413)
			(end 2.2987 7.3533)
			(stroke
				(width 0.1524)
				(type default)
			)
			(layer "B.SilkS")
		)
		(fp_line
			(start 2.032 -0.2413)
			(end 2.2987 -0.2413)
			(stroke
				(width 0.1524)
				(type default)
			)
			(layer "B.SilkS")
		)
		(fp_line
			(start -2.2987 -0.2413)
			(end -2.032 -0.2413)
			(stroke
				(width 0.1524)
				(type default)
			)
			(layer "B.SilkS")
		)
		(fp_line
			(start 2.032 1.524)
			(end 1.7272 1.524)
			(stroke
				(width 0.1524)
				(type default)
			)
			(layer "B.SilkS")
		)
		(fp_line
			(start -2.032 1.524)
			(end -1.7272 1.524)
			(stroke
				(width 0.1524)
				(type default)
			)
			(layer "B.SilkS")
		)
		(fp_line
			(start 2.2987 7.3533)
			(end 1.7272 7.3533)
			(stroke
				(width 0.1524)
				(type default)
			)
			(layer "B.SilkS")
		)
		(fp_line
			(start -1.7272 7.3533)
			(end -2.2987 7.3533)
			(stroke
				(width 0.1524)
				(type default)
			)
			(layer "B.SilkS")
		)
		(fp_line
			(start -2.2987 7.3533)
			(end -2.2987 -0.2413)
			(stroke
				(width 0.1524)
				(type default)
			)
			(layer "B.SilkS")
		)
		(fp_poly
			(pts
				(xy 2.2987 -0.2413) (xy -2.2987 -0.2413) (xy -2.2987 7.3533) (xy 2.2987 7.3533)
			)
			(stroke
				(width 0)
				(type default)
			)
			(fill no)
			(layer "B.CrtYd")
		)
		(fp_line
			(start 2.2987 -0.2413)
			(end -2.2987 -0.2413)
			(stroke
				(width 0.1)
				(type default)
			)
			(layer "B.Fab")
		)
		(fp_line
			(start -2.2987 -0.2413)
			(end -2.2987 7.3533)
			(stroke
				(width 0.1)
				(type default)
			)
			(layer "B.Fab")
		)
		(fp_line
			(start 2.2987 7.3533)
			(end 2.2987 -0.2413)
			(stroke
				(width 0.1)
				(type default)
			)
			(layer "B.Fab")
		)
		(fp_line
			(start -2.2987 7.3533)
			(end 2.2987 7.3533)
			(stroke
				(width 0.1)
				(type default)
			)
			(layer "B.Fab")
		)
		(pad "1" smd rect
			(at 0 0 270)
			(size 2.54 3.048)
			(layers "B.Cu" "B.Mask" "B.Paste")
			(net "PVPP_DEF")
		)
		(pad "2" smd rect
			(at 0 7.112 270)
			(size 2.54 3.048)
			(layers "B.Cu" "B.Mask" "B.Paste")
			(net "GND")
		)
	)
	(footprint ""
		(layer "B.Cu")
		(at 93.548454 -73.51014)
		(property "Reference" "C8P29"
			(at 0 0 0)
			(layer "B.SilkS")
			(hide yes)
			(effects
				(font
					(size 1.27 1.27)
				)
				(justify mirror)
			)
		)
		(property "Value" ""
			(at 0 0 0)
			(layer "B.Fab")
			(effects
				(font
					(size 1.27 1.27)
				)
				(justify mirror)
			)
		)
		(duplicate_pad_numbers_are_jumpers no)
		(fp_poly
			(pts
				(xy 0.7239 -0.2159) (xy -0.7239 -0.2159) (xy -0.7239 1.9939) (xy 0.7239 1.9939)
			)
			(stroke
				(width 0)
				(type default)
			)
			(fill no)
			(layer "B.CrtYd")
		)
		(fp_line
			(start -0.7239 -0.2159)
			(end 0.7239 -0.2159)
			(stroke
				(width 0.1)
				(type default)
			)
			(layer "B.Fab")
		)
		(fp_line
			(start -0.7239 1.9939)
			(end -0.7239 -0.2159)
			(stroke
				(width 0.1)
				(type default)
			)
			(layer "B.Fab")
		)
		(fp_line
			(start 0.7239 -0.2159)
			(end 0.7239 1.9939)
			(stroke
				(width 0.1)
				(type default)
			)
			(layer "B.Fab")
		)
		(fp_line
			(start 0.7239 1.9939)
			(end -0.7239 1.9939)
			(stroke
				(width 0.1)
				(type default)
			)
			(layer "B.Fab")
		)
		(pad "1" smd rect
			(at 0 0 180)
			(size 1.27 1.016)
			(layers "B.Cu" "B.Mask" "B.Paste")
			(net "PVCCIN_CPU1")
		)
		(pad "2" smd rect
			(at 0 1.778 180)
			(size 1.27 1.016)
			(layers "B.Cu" "B.Mask" "B.Paste")
			(net "GND")
		)
		(zone
			(layer "B.Cu")
			(hatch none 0.5)
			(connect_pads
				(clearance 0)
			)
			(min_thickness 0.25)
			(keepout
				(tracks not_allowed)
				(vias allowed)
				(pads allowed)
				(copperpour not_allowed)
				(footprints allowed)
			)
			(placement
				(enabled no)
				(sheetname "")
			)
			(fill
				(thermal_gap 0.5)
				(thermal_bridge_width 0.5)
				(island_removal_mode 0)
			)
			(polygon
				(pts
					(xy 94.183454 -73.00214) (xy 92.913454 -73.00214) (xy 92.913454 -72.24014) (xy 94.183454 -72.24014)
				)
			)
		)
	)
	(footprint ""
		(layer "B.Cu")
		(at 195.1736 -80.2386 90)
		(property "Reference" "CT42"
			(at 0.8382 -0.84963 90)
			(unlocked yes)
			(layer "B.SilkS")
			(effects
				(font
					(size 0.7874 0.5842)
					(thickness 0.1524)
				)
				(justify left mirror)
			)
		)
		(property "Value" ""
			(at 0 0 90)
			(layer "B.Fab")
			(effects
				(font
					(size 1.27 1.27)
				)
				(justify mirror)
			)
		)
		(duplicate_pad_numbers_are_jumpers no)
		(fp_poly
			(pts
				(xy -0.3048 -0.1016) (xy -0.3048 0.9906) (xy 0.3048 0.9906) (xy 0.3048 -0.1016)
			)
			(stroke
				(width 0)
				(type default)
			)
			(fill no)
			(layer "B.CrtYd")
		)
		(fp_line
			(start 0.3048 -0.1016)
			(end 0.3048 0.9906)
			(stroke
				(width 0.1)
				(type default)
			)
			(layer "B.Fab")
		)
		(fp_line
			(start -0.3048 -0.1016)
			(end 0.3048 -0.1016)
			(stroke
				(width 0.1)
				(type default)
			)
			(layer "B.Fab")
		)
		(fp_line
			(start 0.3048 0.9906)
			(end -0.3048 0.9906)
			(stroke
				(width 0.1)
				(type default)
			)
			(layer "B.Fab")
		)
		(fp_line
			(start -0.3048 0.9906)
			(end -0.3048 -0.1016)
			(stroke
				(width 0.1)
				(type default)
			)
			(layer "B.Fab")
		)
		(pad "1" smd rect
			(at 0 0 270)
			(size 0.508 0.508)
			(layers "B.Cu" "B.Mask" "B.Paste")
			(net "A_TSENSE_PVCCIN_CPU0")
		)
		(pad "2" smd rect
			(at 0 0.889 270)
			(size 0.508 0.508)
			(layers "B.Cu" "B.Mask" "B.Paste")
			(net "GND")
		)
		(zone
			(layer "B.Cu")
			(hatch none 0.5)
			(connect_pads
				(clearance 0)
			)
			(min_thickness 0.25)
			(keepout
				(tracks allowed)
				(vias not_allowed)
				(pads allowed)
				(copperpour not_allowed)
				(footprints allowed)
			)
			(placement
				(enabled no)
				(sheetname "")
			)
			(fill
				(thermal_gap 0.5)
				(thermal_bridge_width 0.5)
				(island_removal_mode 0)
			)
			(polygon
				(pts
					(xy 195.4276 -80.4926) (xy 195.4276 -79.9846) (xy 195.8086 -79.9846) (xy 195.8086 -80.4926)
				)
			)
		)
		(zone
			(layer "B.Cu")
			(hatch none 0.5)
			(connect_pads
				(clearance 0)
			)
			(min_thickness 0.25)
			(keepout
				(tracks not_allowed)
				(vias allowed)
				(pads allowed)
				(copperpour not_allowed)
				(footprints allowed)
			)
			(placement
				(enabled no)
				(sheetname "")
			)
			(fill
				(thermal_gap 0.5)
				(thermal_bridge_width 0.5)
				(island_removal_mode 0)
			)
			(polygon
				(pts
					(xy 195.8086 -80.4926) (xy 195.8086 -79.9846) (xy 195.4276 -79.9846) (xy 195.4276 -80.4926)
				)
			)
		)
	)
	(footprint ""
		(layer "B.Cu")
		(at 262.587486 -79.60614 180)
		(property "Reference" "C5P17"
			(at 0 0 0)
			(layer "B.SilkS")
			(hide yes)
			(effects
				(font
					(size 1.27 1.27)
				)
				(justify mirror)
			)
		)
		(property "Value" ""
			(at 0 0 0)
			(layer "B.Fab")
			(effects
				(font
					(size 1.27 1.27)
				)
				(justify mirror)
			)
		)
		(duplicate_pad_numbers_are_jumpers no)
		(fp_poly
			(pts
				(xy 0.7239 -0.2159) (xy -0.7239 -0.2159) (xy -0.7239 1.9939) (xy 0.7239 1.9939)
			)
			(stroke
				(width 0)
				(type default)
			)
			(fill no)
			(layer "B.CrtYd")
		)
		(fp_line
			(start 0.7239 1.9939)
			(end -0.7239 1.9939)
			(stroke
				(width 0.1)
				(type default)
			)
			(layer "B.Fab")
		)
		(fp_line
			(start 0.7239 -0.2159)
			(end 0.7239 1.9939)
			(stroke
				(width 0.1)
				(type default)
			)
			(layer "B.Fab")
		)
		(fp_line
			(start -0.7239 1.9939)
			(end -0.7239 -0.2159)
			(stroke
				(width 0.1)
				(type default)
			)
			(layer "B.Fab")
		)
		(fp_line
			(start -0.7239 -0.2159)
			(end 0.7239 -0.2159)
			(stroke
				(width 0.1)
				(type default)
			)
			(layer "B.Fab")
		)
		(pad "1" smd rect
			(at 0 0)
			(size 1.27 1.016)
			(layers "B.Cu" "B.Mask" "B.Paste")
			(net "PVCCIN_CPU0")
		)
		(pad "2" smd rect
			(at 0 1.778)
			(size 1.27 1.016)
			(layers "B.Cu" "B.Mask" "B.Paste")
			(net "GND")
		)
		(zone
			(layer "B.Cu")
			(hatch none 0.5)
			(connect_pads
				(clearance 0)
			)
			(min_thickness 0.25)
			(keepout
				(tracks not_allowed)
				(vias allowed)
				(pads allowed)
				(copperpour not_allowed)
				(footprints allowed)
			)
			(placement
				(enabled no)
				(sheetname "")
			)
			(fill
				(thermal_gap 0.5)
				(thermal_bridge_width 0.5)
				(island_removal_mode 0)
			)
			(polygon
				(pts
					(xy 261.952486 -80.11414) (xy 263.222486 -80.11414) (xy 263.222486 -80.87614) (xy 261.952486 -80.87614)
				)
			)
		)
	)
)
